(kicad_pcb
	(version 20260206)
	(generator "pcbnew")
	(generator_version "10.0")
	(general
		(thickness 1.6)
		(legacy_teardrops no)
	)
	(paper "A4")
	(title_block
		(title "dpb — 14545-sa.0730WZS0815.brd")
		(comment 1 "Honey Badger (Wiwynn) / footprints 748-751 of 1066")
	)
	(layers
		(0 "F.Cu" signal "TOP")
		(4 "In1.Cu" signal "L2GND")
		(6 "In2.Cu" signal "L3")
		(8 "In3.Cu" signal "L4VCC")
		(10 "In4.Cu" signal "L5VCC")
		(12 "In5.Cu" signal "L6")
		(14 "In6.Cu" signal "L7GND")
		(2 "B.Cu" signal "BOTTOM")
		(9 "F.Adhes" user "F.Adhesive")
		(11 "B.Adhes" user "B.Adhesive")
		(13 "F.Paste" user "Package Geometry/Pastemask Top")
		(15 "B.Paste" user "Package Geometry/Pastemask Bottom")
		(5 "F.SilkS" user "Ref Des/Silkscreen Top")
		(7 "B.SilkS" user "Ref Des/Silkscreen Bottom")
		(1 "F.Mask" user "Board Geometry/Soldermask Top")
		(3 "B.Mask" user "Board Geometry/Soldermask Bottom")
		(17 "Dwgs.User" user "User.Drawings")
		(19 "Cmts.User" user "User.Comments")
		(21 "Eco1.User" user "User.Eco1")
		(23 "Eco2.User" user "User.Eco2")
		(25 "Edge.Cuts" user "Board Geometry/Outline")
		(27 "Margin" user)
		(31 "F.CrtYd" user "Package Geometry/Place Bound Top")
		(29 "B.CrtYd" user "Package Geometry/Place Bound Bottom")
		(35 "F.Fab" user "Ref Des/Assembly Top")
		(33 "B.Fab" user "Ref Des/Assembly Bottom")
	)
	(footprint ""
		(layer "F.Cu")
		(at 221.799912 -40.620696 90)
		(property "Reference" "R159"
			(at 0 0 90)
			(layer "F.SilkS")
			(hide yes)
			(effects
				(font
					(size 1.27 1.27)
				)
			)
		)
		(property "Value" "330R2F-GP"
			(at 0.064008 -3.993896 90)
			(unlocked yes)
			(layer "F.Fab")
			(hide yes)
			(effects
				(font
					(size 1.016 1.016)
					(thickness 0.1524)
				)
			)
		)
		(property "Device Type" "R402H16"
			(at 0.064008 -5.517896 90)
			(unlocked yes)
			(layer "F.Fab")
			(hide yes)
			(effects
				(font
					(size 1.016 1.016)
					(thickness 0.1524)
				)
			)
		)
		(duplicate_pad_numbers_are_jumpers no)
		(fp_line
			(start 0.508 -0.9398)
			(end -0.508 -0.9398)
			(stroke
				(width 0.1524)
				(type default)
			)
			(layer "F.SilkS")
		)
		(fp_line
			(start -0.508 -0.9398)
			(end -0.508 0.9398)
			(stroke
				(width 0.1524)
				(type default)
			)
			(layer "F.SilkS")
		)
		(fp_rect
			(start -0.508 0.9398)
			(end 0.508 -0.9398)
			(stroke
				(width 0)
				(type default)
			)
			(fill no)
			(layer "F.CrtYd")
		)
		(fp_rect
			(start -0.508 0.9398)
			(end 0.508 -0.9398)
			(stroke
				(width 0)
				(type default)
			)
			(fill no)
			(layer "F.Fab")
		)
		(pad "1" smd custom
			(at 0 -0.4445 90)
			(size 0.1397 0.1397)
			(layers "F.Cu" "F.Mask" "F.Paste")
			(net "P3V3_HDD4_LED")
			(options
				(clearance outline)
				(anchor circle)
			)
			(primitives
				(gr_poly
					(pts
						(arc
							(start -0.1778 -0.2794)
							(mid -0.249642 -0.249642)
							(end -0.2794 -0.1778)
						)
						(arc
							(start -0.2794 0.1778)
							(mid -0.249642 0.249642)
							(end -0.1778 0.2794)
						)
						(arc
							(start 0.1778 0.2794)
							(mid 0.249642 0.249642)
							(end 0.2794 0.1778)
						)
						(arc
							(start 0.2794 -0.1778)
							(mid 0.249642 -0.249642)
							(end 0.1778 -0.2794)
						)
					)
					(width 0)
					(fill yes)
				)
			)
		)
		(pad "2" smd custom
			(at 0 0.4445 90)
			(size 0.1397 0.1397)
			(layers "F.Cu" "F.Mask" "F.Paste")
			(net "FLT_HDD4")
			(options
				(clearance outline)
				(anchor circle)
			)
			(primitives
				(gr_poly
					(pts
						(arc
							(start -0.1778 -0.2794)
							(mid -0.249642 -0.249642)
							(end -0.2794 -0.1778)
						)
						(arc
							(start -0.2794 0.1778)
							(mid -0.249642 0.249642)
							(end -0.1778 0.2794)
						)
						(arc
							(start 0.1778 0.2794)
							(mid 0.249642 0.249642)
							(end 0.2794 0.1778)
						)
						(arc
							(start 0.2794 -0.1778)
							(mid 0.249642 -0.249642)
							(end 0.1778 -0.2794)
						)
					)
					(width 0)
					(fill yes)
				)
			)
		)
	)
	(footprint ""
		(layer "F.Cu")
		(at 190.373 -88.9)
		(property "Reference" "R166"
			(at 0 0 0)
			(layer "F.SilkS")
			(hide yes)
			(effects
				(font
					(size 1.27 1.27)
				)
			)
		)
		(property "Value" "200KR2F-L-GP"
			(at 0.064008 -3.993896 0)
			(unlocked yes)
			(layer "F.Fab")
			(hide yes)
			(effects
				(font
					(size 1.016 1.016)
					(thickness 0.1524)
				)
			)
		)
		(property "Device Type" "R402H16"
			(at 0.064008 -5.517896 0)
			(unlocked yes)
			(layer "F.Fab")
			(hide yes)
			(effects
				(font
					(size 1.016 1.016)
					(thickness 0.1524)
				)
			)
		)
		(duplicate_pad_numbers_are_jumpers no)
		(fp_line
			(start -0.508 -0.9398)
			(end -0.508 0.9398)
			(stroke
				(width 0.1524)
				(type default)
			)
			(layer "F.SilkS")
		)
		(fp_line
			(start 0.508 -0.9398)
			(end -0.508 -0.9398)
			(stroke
				(width 0.1524)
				(type default)
			)
			(layer "F.SilkS")
		)
		(fp_rect
			(start -0.508 0.9398)
			(end 0.508 -0.9398)
			(stroke
				(width 0)
				(type default)
			)
			(fill no)
			(layer "F.CrtYd")
		)
		(fp_rect
			(start -0.508 0.9398)
			(end 0.508 -0.9398)
			(stroke
				(width 0)
				(type default)
			)
			(fill no)
			(layer "F.Fab")
		)
		(pad "1" smd custom
			(at 0 -0.4445)
			(size 0.1397 0.1397)
			(layers "F.Cu" "F.Mask" "F.Paste")
			(net "P12V")
			(options
				(clearance outline)
				(anchor circle)
			)
			(primitives
				(gr_poly
					(pts
						(arc
							(start -0.1778 -0.2794)
							(mid -0.249642 -0.249642)
							(end -0.2794 -0.1778)
						)
						(arc
							(start -0.2794 0.1778)
							(mid -0.249642 0.249642)
							(end -0.1778 0.2794)
						)
						(arc
							(start 0.1778 0.2794)
							(mid 0.249642 0.249642)
							(end 0.2794 0.1778)
						)
						(arc
							(start 0.2794 -0.1778)
							(mid 0.249642 -0.249642)
							(end 0.1778 -0.2794)
						)
					)
					(width 0)
					(fill yes)
				)
			)
		)
		(pad "2" smd custom
			(at 0 0.4445)
			(size 0.1397 0.1397)
			(layers "F.Cu" "F.Mask" "F.Paste")
			(net "SW_HDD4_P")
			(options
				(clearance outline)
				(anchor circle)
			)
			(primitives
				(gr_poly
					(pts
						(arc
							(start -0.1778 -0.2794)
							(mid -0.249642 -0.249642)
							(end -0.2794 -0.1778)
						)
						(arc
							(start -0.2794 0.1778)
							(mid -0.249642 0.249642)
							(end -0.1778 0.2794)
						)
						(arc
							(start 0.1778 0.2794)
							(mid 0.249642 0.249642)
							(end 0.2794 0.1778)
						)
						(arc
							(start 0.2794 -0.1778)
							(mid 0.249642 -0.249642)
							(end 0.1778 -0.2794)
						)
					)
					(width 0)
					(fill yes)
				)
			)
		)
	)
	(footprint ""
		(layer "F.Cu")
		(at 61.213746 -21.8567)
		(property "Reference" "PC23"
			(at 0 0 0)
			(layer "F.SilkS")
			(hide yes)
			(effects
				(font
					(size 1.27 1.27)
				)
			)
		)
		(property "Value" "SC4D7U25V5KX-GP"
			(at -0.0762 -6.1214 0)
			(unlocked yes)
			(layer "F.Fab")
			(hide yes)
			(effects
				(font
					(size 1.016 1.016)
					(thickness 0.1524)
				)
			)
		)
		(property "Device Type" "C805H54"
			(at -0.0762 -8.1534 0)
			(unlocked yes)
			(layer "F.Fab")
			(hide yes)
			(effects
				(font
					(size 1.016 1.016)
					(thickness 0.1524)
				)
			)
		)
		(duplicate_pad_numbers_are_jumpers no)
		(fp_line
			(start 0.635 0)
			(end -0.635 0)
			(stroke
				(width 0.508)
				(type default)
			)
			(layer "F.SilkS")
		)
		(fp_rect
			(start -0.9652 1.778)
			(end 0.9652 -1.778)
			(stroke
				(width 0)
				(type default)
			)
			(fill no)
			(layer "F.CrtYd")
		)
		(fp_poly
			(pts
				(xy -0.9652 -1.778) (xy 0.9652 -1.778) (xy 0.9652 1.778) (xy -0.9652 1.778)
			)
			(stroke
				(width 0)
				(type default)
			)
			(fill no)
			(layer "F.Fab")
		)
		(pad "1" smd rect
			(at 0 -0.9652)
			(size 1.397 1.143)
			(layers "F.Cu" "F.Mask" "F.Paste")
			(net "P5VB_VDD")
		)
		(pad "2" smd rect
			(at 0 0.9652)
			(size 1.397 1.143)
			(layers "F.Cu" "F.Mask" "F.Paste")
			(net "GND")
		)
	)
	(footprint ""
		(layer "F.Cu")
		(at 233.247946 -246.6594 90)
		(property "Reference" "Q36"
			(at 0 0 90)
			(layer "F.SilkS")
			(hide yes)
			(effects
				(font
					(size 1.27 1.27)
				)
			)
		)
		(property "Value" "PMBS3904-1-GP"
			(at 0 -9.0932 90)
			(unlocked yes)
			(layer "F.Fab")
			(hide yes)
			(effects
				(font
					(size 1.016 1.016)
					(thickness 0.1524)
				)
			)
		)
		(property "Device Type" "SOT-23-10H44"
			(at 0 -10.6172 90)
			(unlocked yes)
			(layer "F.Fab")
			(hide yes)
			(effects
				(font
					(size 1.016 1.016)
					(thickness 0.1524)
				)
			)
		)
		(duplicate_pad_numbers_are_jumpers no)
		(fp_line
			(start 1.651 -1.778)
			(end -1.651 -1.778)
			(stroke
				(width 0.1524)
				(type default)
			)
			(layer "F.SilkS")
		)
		(fp_line
			(start -1.651 -1.778)
			(end -1.651 1.778)
			(stroke
				(width 0.1524)
				(type default)
			)
			(layer "F.SilkS")
		)
		(fp_line
			(start 1.651 1.778)
			(end 1.651 -1.778)
			(stroke
				(width 0.1524)
				(type default)
			)
			(layer "F.SilkS")
		)
		(fp_line
			(start -1.651 1.778)
			(end 1.651 1.778)
			(stroke
				(width 0.1524)
				(type default)
			)
			(layer "F.SilkS")
		)
		(fp_line
			(start -0.9906 1.86309)
			(end -0.701294 2.15265)
			(stroke
				(width 0.0127)
				(type default)
			)
			(layer "F.SilkS")
		)
		(fp_line
			(start -0.994156 1.8669)
			(end -0.987044 1.8669)
			(stroke
				(width 0.0127)
				(type default)
			)
			(layer "F.SilkS")
		)
		(fp_line
			(start -1.003808 1.876552)
			(end -0.977646 1.876552)
			(stroke
				(width 0.0127)
				(type default)
			)
			(layer "F.SilkS")
		)
		(fp_line
			(start -0.635 1.8796)
			(end -1.7526 1.8796)
			(stroke
				(width 0.3302)
				(type default)
			)
			(layer "F.SilkS")
		)
		(fp_line
			(start -1.7526 1.8796)
			(end -1.7526 0.9906)
			(stroke
				(width 0.3302)
				(type default)
			)
			(layer "F.SilkS")
		)
		(fp_line
			(start -1.013206 1.88595)
			(end -0.967994 1.88595)
			(stroke
				(width 0.0127)
				(type default)
			)
			(layer "F.SilkS")
		)
		(fp_line
			(start -1.022858 1.895602)
			(end -0.958596 1.895602)
			(stroke
				(width 0.0127)
				(type default)
			)
			(layer "F.SilkS")
		)
		(fp_line
			(start -1.032256 1.905)
			(end -0.948944 1.905)
			(stroke
				(width 0.0127)
				(type default)
			)
			(layer "F.SilkS")
		)
		(fp_line
			(start -1.041908 1.914652)
			(end -0.939546 1.914652)
			(stroke
				(width 0.0127)
				(type default)
			)
			(layer "F.SilkS")
		)
		(fp_line
			(start -1.051306 1.92405)
			(end -0.929894 1.92405)
			(stroke
				(width 0.0127)
				(type default)
			)
			(layer "F.SilkS")
		)
		(fp_line
			(start -1.060958 1.933702)
			(end -0.920496 1.933702)
			(stroke
				(width 0.0127)
				(type default)
			)
			(layer "F.SilkS")
		)
		(fp_line
			(start -1.070356 1.9431)
			(end -0.910844 1.9431)
			(stroke
				(width 0.0127)
				(type default)
			)
			(layer "F.SilkS")
		)
		(fp_line
			(start -1.080008 1.952752)
			(end -0.901446 1.952752)
			(stroke
				(width 0.0127)
				(type default)
			)
			(layer "F.SilkS")
		)
		(fp_line
			(start -1.089406 1.96215)
			(end -0.891794 1.96215)
			(stroke
				(width 0.0127)
				(type default)
			)
			(layer "F.SilkS")
		)
		(fp_line
			(start -1.099058 1.971802)
			(end -0.882396 1.971802)
			(stroke
				(width 0.0127)
				(type default)
			)
			(layer "F.SilkS")
		)
		(fp_line
			(start -1.108456 1.9812)
			(end -0.872744 1.9812)
			(stroke
				(width 0.0127)
				(type default)
			)
			(layer "F.SilkS")
		)
		(fp_line
			(start -1.118108 1.990852)
			(end -0.863346 1.990852)
			(stroke
				(width 0.0127)
				(type default)
			)
			(layer "F.SilkS")
		)
		(fp_line
			(start -1.127506 2.00025)
			(end -0.853694 2.00025)
			(stroke
				(width 0.0127)
				(type default)
			)
			(layer "F.SilkS")
		)
		(fp_line
			(start -1.137158 2.009902)
			(end -0.844296 2.009902)
			(stroke
				(width 0.0127)
				(type default)
			)
			(layer "F.SilkS")
		)
		(fp_line
			(start -1.146556 2.0193)
			(end -0.834644 2.0193)
			(stroke
				(width 0.0127)
				(type default)
			)
			(layer "F.SilkS")
		)
		(fp_line
			(start -1.156208 2.028952)
			(end -0.825246 2.028952)
			(stroke
				(width 0.0127)
				(type default)
			)
			(layer "F.SilkS")
		)
		(fp_line
			(start -1.165606 2.03835)
			(end -0.815594 2.03835)
			(stroke
				(width 0.0127)
				(type default)
			)
			(layer "F.SilkS")
		)
		(fp_line
			(start -1.175258 2.048002)
			(end -0.806196 2.048002)
			(stroke
				(width 0.0127)
				(type default)
			)
			(layer "F.SilkS")
		)
		(fp_line
			(start -1.184656 2.0574)
			(end -0.796544 2.0574)
			(stroke
				(width 0.0127)
				(type default)
			)
			(layer "F.SilkS")
		)
		(fp_line
			(start -1.194308 2.067052)
			(end -0.787146 2.067052)
			(stroke
				(width 0.0127)
				(type default)
			)
			(layer "F.SilkS")
		)
		(fp_line
			(start -1.203706 2.07645)
			(end -0.777494 2.07645)
			(stroke
				(width 0.0127)
				(type default)
			)
			(layer "F.SilkS")
		)
		(fp_line
			(start -1.213358 2.086102)
			(end -0.768096 2.086102)
			(stroke
				(width 0.0127)
				(type default)
			)
			(layer "F.SilkS")
		)
		(fp_line
			(start -1.222756 2.0955)
			(end -0.758444 2.0955)
			(stroke
				(width 0.0127)
				(type default)
			)
			(layer "F.SilkS")
		)
		(fp_line
			(start -1.232408 2.105152)
			(end -0.749046 2.105152)
			(stroke
				(width 0.0127)
				(type default)
			)
			(layer "F.SilkS")
		)
		(fp_line
			(start -1.241806 2.11455)
			(end -0.739394 2.11455)
			(stroke
				(width 0.0127)
				(type default)
			)
			(layer "F.SilkS")
		)
		(fp_line
			(start -1.251458 2.124202)
			(end -0.729996 2.124202)
			(stroke
				(width 0.0127)
				(type default)
			)
			(layer "F.SilkS")
		)
		(fp_line
			(start -1.260856 2.1336)
			(end -0.720344 2.1336)
			(stroke
				(width 0.0127)
				(type default)
			)
			(layer "F.SilkS")
		)
		(fp_line
			(start -0.719074 2.145538)
			(end -1.265936 2.14122)
			(stroke
				(width 0.0127)
				(type default)
			)
			(layer "F.SilkS")
		)
		(fp_line
			(start -1.279398 2.152142)
			(end -0.9906 1.86309)
			(stroke
				(width 0.0127)
				(type default)
			)
			(layer "F.SilkS")
		)
		(fp_line
			(start -0.71628 2.15265)
			(end -1.26492 2.15265)
			(stroke
				(width 0.0127)
				(type default)
			)
			(layer "F.SilkS")
		)
		(fp_line
			(start -1.279144 2.15265)
			(end -0.701294 2.15265)
			(stroke
				(width 0.0127)
				(type default)
			)
			(layer "F.SilkS")
		)
		(fp_poly
			(pts
				(xy -1.285748 2.159) (xy -1.285748 1.8796) (xy -1.778 1.8796) (xy -1.778 -1.8796) (xy 1.778 -1.8796)
				(xy 1.778 1.8796) (xy -0.694944 1.8796) (xy -0.694944 2.159)
			)
			(stroke
				(width 0)
				(type default)
			)
			(fill no)
			(layer "F.CrtYd")
		)
		(fp_poly
			(pts
				(xy -1.285748 2.159) (xy -1.285748 1.8796) (xy -1.778 1.8796) (xy -1.778 -1.8796) (xy 1.778 -1.8796)
				(xy 1.778 1.8796) (xy -0.694944 1.8796) (xy -0.694944 2.159)
			)
			(stroke
				(width 0)
				(type default)
			)
			(fill no)
			(layer "F.Fab")
		)
		(pad "1" smd rect
			(at -0.98425 0.9525 90)
			(size 0.762 1.143)
			(layers "F.Cu" "F.Mask" "F.Paste")
			(net "FLT_HDD2_B")
		)
		(pad "2" smd rect
			(at 0.98425 0.9525 90)
			(size 0.762 1.143)
			(layers "F.Cu" "F.Mask" "F.Paste")
			(net "GND")
		)
		(pad "3" smd rect
			(at 0 -0.9525 90)
			(size 0.762 1.143)
			(layers "F.Cu" "F.Mask" "F.Paste")
			(net "DRIVE_ACT_2")
		)
	)
)
